# TIMECARD (Time Appliance Project (Time Card)) — schematic netlist excerpt (pin names and nets, part order shuffled) for the footprints in the layout excerpt that follows; sources: Cadence DE-HDL packaged netlist, KiCad conversion of R4006-B0001-02_R01.brd

R484  RESISTOR  1KOHM 1%  pkg SMC_0402R_H016  page 24 : \1\ = SG ; \2\ = UNNAMED_524_RESISTOR_I463_2
C257  CAPACITOR  10UF 25V 20%  pkg SMC_0805R_H057  page 29 : \1\ = VIN_XP1R0V ; \2\ = SG

(kicad_pcb
	(version 20260206)
	(generator "pcbnew")
	(generator_version "10.0")
	(general
		(thickness 1.6)
		(legacy_teardrops no)
	)
	(paper "A4")
	(title_block
		(title "timecard-production-celestica-r4006 — R4006-B0001-02_R01.brd")
		(comment 1 "Time Appliance Project (Time Card) / footprints 250-251 of 1113")
	)
	(layers
		(0 "F.Cu" signal "TOP")
		(4 "In1.Cu" signal "L02_GND1")
		(6 "In2.Cu" signal "L03_SIG1")
		(8 "In3.Cu" signal "L04_GND2")
		(10 "In4.Cu" signal "L05_VCC1")
		(12 "In5.Cu" signal "L06_VCC2")
		(14 "In6.Cu" signal "L07_GND3")
		(16 "In7.Cu" signal "L08_SIG2")
		(18 "In8.Cu" signal "L09_GND4")
		(2 "B.Cu" signal "BOTTOM")
		(9 "F.Adhes" user "F.Adhesive")
		(11 "B.Adhes" user "B.Adhesive")
		(13 "F.Paste" user "Package Geometry/Pastemask Top")
		(15 "B.Paste" user "Package Geometry/Pastemask Bottom")
		(5 "F.SilkS" user "Ref Des/Silkscreen Top")
		(7 "B.SilkS" user "Ref Des/Silkscreen Bottom")
		(1 "F.Mask" user "Board Geometry/Soldermask Top")
		(3 "B.Mask" user "Board Geometry/Soldermask Bottom")
		(17 "Dwgs.User" user "User.Drawings")
		(19 "Cmts.User" user "User.Comments")
		(21 "Eco1.User" user "User.Eco1")
		(23 "Eco2.User" user "User.Eco2")
		(25 "Edge.Cuts" user "Board Geometry/Outline")
		(27 "Margin" user)
		(31 "F.CrtYd" user "Package Geometry/Place Bound Top")
		(29 "B.CrtYd" user "Package Geometry/Place Bound Bottom")
		(35 "F.Fab" user "Ref Des/Assembly Top")
		(33 "B.Fab" user "Ref Des/Assembly Bottom")
	)
	(footprint ""
		(layer "F.Cu")
		(at 133.858 -22.098 180)
		(property "Reference" "R484"
			(at 0.127 5.04063 0)
			(unlocked yes)
			(layer "F.SilkS")
			(effects
				(font
					(size 0.7874 0.5842)
					(thickness 0.1524)
				)
			)
		)
		(property "Value" "VAL*"
			(at 0.02032 2.13233 180)
			(unlocked yes)
			(layer "F.Fab")
			(hide yes)
			(effects
				(font
					(size 0.7874 0.5842)
					(thickness 0.1524)
				)
			)
		)
		(property "Tolerance" "TOL*"
			(at 0.044704 3.05435 180)
			(unlocked yes)
			(layer "Cmts.User")
			(hide yes)
			(effects
				(font
					(size 0.7874 0.5842)
					(thickness 0.1524)
				)
			)
		)
		(property "User Part Number" "PARTNUM*"
			(at 0.02032 4.024884 180)
			(unlocked yes)
			(layer "Cmts.User")
			(hide yes)
			(effects
				(font
					(size 0.7874 0.5842)
					(thickness 0.1524)
				)
			)
		)
		(property "Device Type" "RESISTOR-G155-11001-01,1KOHM,1%"
			(at 0.008382 1.210564 180)
			(unlocked yes)
			(layer "F.Fab")
			(hide yes)
			(effects
				(font
					(size 0.7874 0.5842)
					(thickness 0.1524)
				)
			)
		)
		(duplicate_pad_numbers_are_jumpers no)
		(fp_line
			(start 1.143 0.5588)
			(end 1.143 -0.5588)
			(stroke
				(width 0.1)
				(type default)
			)
			(layer "F.SilkS")
		)
		(fp_line
			(start 1.143 -0.5588)
			(end -1.143 -0.5588)
			(stroke
				(width 0.1)
				(type default)
			)
			(layer "F.SilkS")
		)
		(fp_line
			(start -1.143 0.5588)
			(end 1.143 0.5588)
			(stroke
				(width 0.1)
				(type default)
			)
			(layer "F.SilkS")
		)
		(fp_line
			(start -1.143 -0.5588)
			(end -1.143 0.5588)
			(stroke
				(width 0.1)
				(type default)
			)
			(layer "F.SilkS")
		)
		(fp_poly
			(pts
				(xy -1.143 0.5588) (xy 1.143 0.5588) (xy 1.143 -0.5588) (xy -1.143 -0.5588)
			)
			(stroke
				(width 0)
				(type default)
			)
			(fill no)
			(layer "F.CrtYd")
		)
		(fp_line
			(start 0.508 0.3048)
			(end 0.508 -0.3048)
			(stroke
				(width 0.1)
				(type default)
			)
			(layer "F.Fab")
		)
		(fp_line
			(start 0.508 -0.3048)
			(end -0.508 -0.3048)
			(stroke
				(width 0.1)
				(type default)
			)
			(layer "F.Fab")
		)
		(fp_line
			(start -0.508 0.3048)
			(end 0.508 0.3048)
			(stroke
				(width 0.1)
				(type default)
			)
			(layer "F.Fab")
		)
		(fp_line
			(start -0.508 -0.3048)
			(end -0.508 0.3048)
			(stroke
				(width 0.1)
				(type default)
			)
			(layer "F.Fab")
		)
		(pad "1" smd rect
			(at -0.5334 0 180)
			(size 0.7112 0.6096)
			(layers "F.Cu" "F.Mask" "F.Paste")
			(net "SG")
		)
		(pad "2" smd rect
			(at 0.5334 0 180)
			(size 0.7112 0.6096)
			(layers "F.Cu" "F.Mask" "F.Paste")
			(net "UNNAMED_524_RESISTOR_I463_2")
		)
		(zone
			(layer "F.Cu")
			(hatch none 0.5)
			(connect_pads
				(clearance 0)
			)
			(min_thickness 0.25)
			(keepout
				(tracks allowed)
				(vias not_allowed)
				(pads allowed)
				(copperpour not_allowed)
				(footprints allowed)
			)
			(placement
				(enabled no)
				(sheetname "")
			)
			(fill
				(thermal_gap 0.5)
				(thermal_bridge_width 0.5)
				(island_removal_mode 0)
			)
			(polygon
				(pts
					(xy 133.9342 -22.4028) (xy 133.7818 -22.4028) (xy 133.7818 -21.7932) (xy 133.9342 -21.7932)
				)
			)
		)
		(zone
			(layer "F.Cu")
			(hatch none 0.5)
			(connect_pads
				(clearance 0)
			)
			(min_thickness 0.25)
			(keepout
				(tracks not_allowed)
				(vias allowed)
				(pads allowed)
				(copperpour not_allowed)
				(footprints allowed)
			)
			(placement
				(enabled no)
				(sheetname "")
			)
			(fill
				(thermal_gap 0.5)
				(thermal_bridge_width 0.5)
				(island_removal_mode 0)
			)
			(polygon
				(pts
					(xy 133.9342 -22.4028) (xy 133.7818 -22.4028) (xy 133.7818 -21.7932) (xy 133.9342 -21.7932)
				)
			)
		)
	)
	(footprint ""
		(layer "F.Cu")
		(at 146.304 -53.848 -90)
		(property "Reference" "C257"
			(at 1.27 -2.70637 90)
			(unlocked yes)
			(layer "F.SilkS")
			(effects
				(font
					(size 0.7874 0.5842)
					(thickness 0.1524)
				)
			)
		)
		(property "Value" "VAL*"
			(at 0.0762 3.134106 270)
			(unlocked yes)
			(layer "F.Fab")
			(hide yes)
			(effects
				(font
					(size 0.7874 0.5842)
					(thickness 0.1524)
				)
			)
		)
		(property "Device Type" "CAPACITOR-G107-0F106-EM,10UF,2A"
			(at 0.0508 2.194306 270)
			(unlocked yes)
			(layer "F.Fab")
			(hide yes)
			(effects
				(font
					(size 0.7874 0.5842)
					(thickness 0.1524)
				)
			)
		)
		(property "User Part Number" "PARTNUM*"
			(at 0.1016 5.013706 270)
			(unlocked yes)
			(layer "Cmts.User")
			(hide yes)
			(effects
				(font
					(size 0.7874 0.5842)
					(thickness 0.1524)
				)
			)
		)
		(property "Tolerance" "TOL*"
			(at 0.0762 4.048506 270)
			(unlocked yes)
			(layer "Cmts.User")
			(hide yes)
			(effects
				(font
					(size 0.7874 0.5842)
					(thickness 0.1524)
				)
			)
		)
		(duplicate_pad_numbers_are_jumpers no)
		(fp_line
			(start -1.5748 0.9398)
			(end 1.5748 0.9398)
			(stroke
				(width 0.1)
				(type default)
			)
			(layer "F.SilkS")
		)
		(fp_line
			(start 1.5748 0.9398)
			(end 1.5748 -0.9398)
			(stroke
				(width 0.1)
				(type default)
			)
			(layer "F.SilkS")
		)
		(fp_line
			(start -1.5748 -0.9398)
			(end -1.5748 0.9398)
			(stroke
				(width 0.1)
				(type default)
			)
			(layer "F.SilkS")
		)
		(fp_line
			(start 1.5748 -0.9398)
			(end -1.5748 -0.9398)
			(stroke
				(width 0.1)
				(type default)
			)
			(layer "F.SilkS")
		)
		(fp_rect
			(start 1.5748 0.9398)
			(end -1.5748 -0.9398)
			(stroke
				(width 0)
				(type default)
			)
			(fill no)
			(layer "F.CrtYd")
		)
		(fp_line
			(start -1.016 0.635)
			(end 1.016 0.635)
			(stroke
				(width 0.1)
				(type default)
			)
			(layer "F.Fab")
		)
		(fp_line
			(start 1.016 0.635)
			(end 1.016 -0.635)
			(stroke
				(width 0.1)
				(type default)
			)
			(layer "F.Fab")
		)
		(fp_line
			(start -1.016 -0.635)
			(end -1.016 0.635)
			(stroke
				(width 0.1)
				(type default)
			)
			(layer "F.Fab")
		)
		(fp_line
			(start 1.016 -0.635)
			(end -1.016 -0.635)
			(stroke
				(width 0.1)
				(type default)
			)
			(layer "F.Fab")
		)
		(pad "1" smd rect
			(at -0.8382 0 270)
			(size 0.9652 1.3716)
			(layers "F.Cu" "F.Mask" "F.Paste")
			(net "VIN_XP1R0V")
		)
		(pad "2" smd rect
			(at 0.8382 0 270)
			(size 0.9652 1.3716)
			(layers "F.Cu" "F.Mask" "F.Paste")
			(net "SG")
		)
		(zone
			(layer "F.Cu")
			(hatch none 0.5)
			(connect_pads
				(clearance 0)
			)
			(min_thickness 0.25)
			(keepout
				(tracks allowed)
				(vias not_allowed)
				(pads allowed)
				(copperpour not_allowed)
				(footprints allowed)
			)
			(placement
				(enabled no)
				(sheetname "")
			)
			(fill
				(thermal_gap 0.5)
				(thermal_bridge_width 0.5)
				(island_removal_mode 0)
			)
			(polygon
				(pts
					(xy 145.669 -53.6194) (xy 146.939 -53.6194) (xy 146.939 -54.0766) (xy 145.669 -54.0766)
				)
			)
		)
	)
)
